(kicad_pcb
	(version 20241229)
	(generator "pcbnew")
	(generator_version "9.0")
	(general
		(thickness 1.294)
		(legacy_teardrops no)
	)
	(paper "A3")
	(title_block
		(title "Kintex 410T devboard")
		(date "2024-04-03")
		(rev "1.1.2")
		(comment 9 "footprint 170 of 975 (U1), pads 723-786 of 900")
	)
	(layers
		(0 "F.Cu" mixed)
		(4 "In1.Cu" power)
		(6 "In2.Cu" power)
		(8 "In3.Cu" mixed)
		(10 "In4.Cu" power)
		(12 "In5.Cu" mixed)
		(14 "In6.Cu" power)
		(16 "In7.Cu" mixed)
		(18 "In8.Cu" power)
		(2 "B.Cu" mixed)
		(9 "F.Adhes" user "F.Adhesive")
		(11 "B.Adhes" user "B.Adhesive")
		(13 "F.Paste" user)
		(15 "B.Paste" user)
		(5 "F.SilkS" user "F.Silkscreen")
		(7 "B.SilkS" user "B.Silkscreen")
		(1 "F.Mask" user)
		(3 "B.Mask" user)
		(17 "Dwgs.User" user "User.Drawings")
		(19 "Cmts.User" user "User.Comments")
		(21 "Eco1.User" user "User.Eco1")
		(23 "Eco2.User" user "User.Eco2")
		(25 "Edge.Cuts" user)
		(27 "Margin" user)
		(31 "F.CrtYd" user "F.Courtyard")
		(29 "B.CrtYd" user "B.Courtyard")
		(35 "F.Fab" user)
		(33 "B.Fab" user)
	)
	(footprint "antmicro-footprints:BGA-900_31x31mm_Layout30x30_P1x1mm_FFG900"
		(locked yes)
		(layer "F.Cu")
		(at 200 130)
		(property "Reference" "U1"
			(at -15.74 -15.78 0)
			(layer "F.SilkS")
			(effects
				(font
					(size 0.7 0.7)
					(thickness 0.15)
				)
				(justify left bottom)
			)
		)
		(property "Value" "XC7K410T-2FFG900I"
			(at -4.436 17.635 0)
			(layer "F.Fab")
			(effects
				(font
					(size 0.7 0.7)
					(thickness 0.15)
				)
				(justify left bottom)
			)
		)
		(property "Description" "FPGA, Kintex-7, MMCM, PLL, 350 I/O's, 710 MHz, 406720 Cells, 970 mV to 1.03 V, FCBGA-900"
			(at 0 0 0)
			(layer "F.Fab")
			(hide yes)
			(effects
				(font
					(size 1.27 1.27)
					(thickness 0.15)
				)
			)
		)
		(property "Author" "Antmicro"
			(at 0 0 0)
			(layer "F.Fab")
			(hide yes)
			(effects
				(font
					(size 1 1)
					(thickness 0.15)
				)
			)
		)
		(property "License" "Apache-2.0"
			(at 0 0 0)
			(layer "F.Fab")
			(hide yes)
			(effects
				(font
					(size 1 1)
					(thickness 0.15)
				)
			)
		)
		(property "MPN" "XC7K410T-2FFG900I"
			(at 0 0 0)
			(layer "F.Fab")
			(hide yes)
			(effects
				(font
					(size 1 1)
					(thickness 0.15)
				)
			)
		)
		(property "Manufacturer" "AMD-Xilinx"
			(at 0 0 0)
			(layer "F.Fab")
			(hide yes)
			(effects
				(font
					(size 1 1)
					(thickness 0.15)
				)
			)
		)
		(sheetname "FPGA supply")
		(sheetfile "fpga-supply.kicad_sch")
		(attr smd)
		(pad "R3" smd circle
			(at -12.5 -0.5)
			(size 0.5 0.5)
			(property pad_prop_bga)
			(layers "F.Cu" "F.Mask" "F.Paste")
			(net 282 "/FMC+ HSPC/GTX116.RX3_N")
			(pinfunction "MGTXRXN1_116")
			(pintype "bidirectional")
			(die_length 12.761)
			(solder_mask_margin 0.02)
		)
		(pad "R4" smd circle
			(at -11.5 -0.5)
			(size 0.5 0.5)
			(property pad_prop_bga)
			(layers "F.Cu" "F.Mask" "F.Paste")
			(net 287 "/FMC+ HSPC/GTX116.RX3_P")
			(pinfunction "MGTXRXP1_116")
			(pintype "bidirectional")
			(die_length 12.836)
			(solder_mask_margin 0.02)
		)
		(pad "R5" smd circle
			(at -10.5 -0.5)
			(size 0.5 0.5)
			(property pad_prop_bga)
			(layers "F.Cu" "F.Mask" "F.Paste")
			(net 8 "+1V2_MGTAVTT")
			(pinfunction "MGTAVTT")
			(pintype "passive")
			(solder_mask_margin 0.02)
		)
		(pad "R6" smd circle
			(at -9.5 -0.5)
			(size 0.5 0.5)
			(property pad_prop_bga)
			(layers "F.Cu" "F.Mask" "F.Paste")
			(net 1 "GND")
			(pinfunction "GND")
			(pintype "passive")
			(solder_mask_margin 0.02)
		)
		(pad "R7" smd circle
			(at -8.5 -0.5)
			(size 0.5 0.5)
			(property pad_prop_bga)
			(layers "F.Cu" "F.Mask" "F.Paste")
			(net 630 "/FMC+ HSPC/GTX115.REFCLK0_N")
			(pinfunction "MGTREFCLK0N_115")
			(pintype "bidirectional")
			(die_length 7.794)
			(solder_mask_margin 0.02)
		)
		(pad "R8" smd circle
			(at -7.5 -0.5)
			(size 0.5 0.5)
			(property pad_prop_bga)
			(layers "F.Cu" "F.Mask" "F.Paste")
			(net 628 "/FMC+ HSPC/GTX115.REFCLK0_P")
			(pinfunction "MGTREFCLK0P_115")
			(pintype "bidirectional")
			(die_length 7.477)
			(solder_mask_margin 0.02)
		)
		(pad "R9" smd circle
			(at -6.5 -0.5)
			(size 0.5 0.5)
			(property pad_prop_bga)
			(layers "F.Cu" "F.Mask" "F.Paste")
			(net 1 "GND")
			(pinfunction "GND")
			(pintype "passive")
			(solder_mask_margin 0.02)
		)
		(pad "R10" smd circle
			(at -5.5 -0.5)
			(size 0.5 0.5)
			(property pad_prop_bga)
			(layers "F.Cu" "F.Mask" "F.Paste")
			(net 650 "+1V0")
			(pinfunction "VCCINT")
			(pintype "passive")
			(solder_mask_margin 0.02)
		)
		(pad "R11" smd circle
			(at -4.5 -0.5)
			(size 0.5 0.5)
			(property pad_prop_bga)
			(layers "F.Cu" "F.Mask" "F.Paste")
			(net 1 "GND")
			(pinfunction "GND")
			(pintype "passive")
			(solder_mask_margin 0.02)
		)
		(pad "R12" smd circle
			(at -3.5 -0.5)
			(size 0.5 0.5)
			(property pad_prop_bga)
			(layers "F.Cu" "F.Mask" "F.Paste")
			(net 650 "+1V0")
			(pinfunction "VCCINT")
			(pintype "passive")
			(solder_mask_margin 0.02)
		)
		(pad "R13" smd circle
			(at -2.5 -0.5)
			(size 0.5 0.5)
			(property pad_prop_bga)
			(layers "F.Cu" "F.Mask" "F.Paste")
			(net 1 "GND")
			(pinfunction "GND")
			(pintype "passive")
			(solder_mask_margin 0.02)
		)
		(pad "R14" smd circle
			(at -1.5 -0.5)
			(size 0.5 0.5)
			(property pad_prop_bga)
			(layers "F.Cu" "F.Mask" "F.Paste")
			(net 1 "GND")
			(pinfunction "VREFN_0")
			(pintype "bidirectional")
			(die_length 10.643)
			(solder_mask_margin 0.02)
		)
		(pad "R15" smd circle
			(at -0.5 -0.5)
			(size 0.5 0.5)
			(property pad_prop_bga)
			(layers "F.Cu" "F.Mask" "F.Paste")
			(net 1395 "unconnected-(U1I-VP_0-PadR15)")
			(pinfunction "VP_0")
			(pintype "bidirectional+no_connect")
			(die_length 9.522)
			(solder_mask_margin 0.02)
		)
		(pad "R16" smd circle
			(at 0.5 -0.5)
			(size 0.5 0.5)
			(property pad_prop_bga)
			(layers "F.Cu" "F.Mask" "F.Paste")
			(net 650 "+1V0")
			(pinfunction "VCCBRAM")
			(pintype "passive")
			(solder_mask_margin 0.02)
		)
		(pad "R17" smd circle
			(at 1.5 -0.5)
			(size 0.5 0.5)
			(property pad_prop_bga)
			(layers "F.Cu" "F.Mask" "F.Paste")
			(net 1 "GND")
			(pinfunction "GND")
			(pintype "passive")
			(solder_mask_margin 0.02)
		)
		(pad "R18" smd circle
			(at 2.5 -0.5)
			(size 0.5 0.5)
			(property pad_prop_bga)
			(layers "F.Cu" "F.Mask" "F.Paste")
			(net 650 "+1V0")
			(pinfunction "VCCINT")
			(pintype "passive")
			(solder_mask_margin 0.02)
		)
		(pad "R19" smd circle
			(at 3.5 -0.5)
			(size 0.5 0.5)
			(property pad_prop_bga)
			(layers "F.Cu" "F.Mask" "F.Paste")
			(net 403 "/FPGA Bank 14 & 15/SYSTEM_FLASH.DQ2")
			(pinfunction "IO_0_14")
			(pintype "bidirectional")
			(die_length 7.988)
			(solder_mask_margin 0.02)
		)
		(pad "R20" smd circle
			(at 4.5 -0.5)
			(size 0.5 0.5)
			(property pad_prop_bga)
			(layers "F.Cu" "F.Mask" "F.Paste")
			(net 1386 "/SUP_MCU.SCLK1")
			(pinfunction "IO_L2P_T0_D02_14")
			(pintype "bidirectional")
			(die_length 11.33)
			(solder_mask_margin 0.02)
		)
		(pad "R21" smd circle
			(at 5.5 -0.5)
			(size 0.5 0.5)
			(property pad_prop_bga)
			(layers "F.Cu" "F.Mask" "F.Paste")
			(net 1294 "/USB_SPI.MISO")
			(pinfunction "IO_L2N_T0_D03_14")
			(pintype "bidirectional")
			(die_length 9.937)
			(solder_mask_margin 0.02)
		)
		(pad "R22" smd circle
			(at 6.5 -0.5)
			(size 0.5 0.5)
			(property pad_prop_bga)
			(layers "F.Cu" "F.Mask" "F.Paste")
			(net 1 "GND")
			(pinfunction "GND")
			(pintype "passive")
			(solder_mask_margin 0.02)
		)
		(pad "R23" smd circle
			(at 7.5 -0.5)
			(size 0.5 0.5)
			(property pad_prop_bga)
			(layers "F.Cu" "F.Mask" "F.Paste")
			(net 566 "/FPGA Bank 14 & 15/CFG_PUDC")
			(pinfunction "IO_L3P_T0_DQS_PUDC_B_14")
			(pintype "bidirectional")
			(die_length 10.245)
			(solder_mask_margin 0.02)
		)
		(pad "R24" smd circle
			(at 8.5 -0.5)
			(size 0.5 0.5)
			(property pad_prop_bga)
			(layers "F.Cu" "F.Mask" "F.Paste")
			(net 398 "/FPGA Bank 14 & 15/SYSTEM_FLASH.DQ3")
			(pinfunction "IO_L3N_T0_DQS_EMCCLK_14")
			(pintype "bidirectional")
			(die_length 10.11)
			(solder_mask_margin 0.02)
		)
		(pad "R25" smd circle
			(at 9.5 -0.5)
			(size 0.5 0.5)
			(property pad_prop_bga)
			(layers "F.Cu" "F.Mask" "F.Paste")
			(net 43 "/FPGA Bank 14 & 15/SYSTEM_FLASH.DQ1")
			(pinfunction "IO_L1N_T0_D01_DIN_14")
			(pintype "bidirectional")
			(die_length 10.823)
			(solder_mask_margin 0.02)
		)
		(pad "R26" smd circle
			(at 10.5 -0.5)
			(size 0.5 0.5)
			(property pad_prop_bga)
			(layers "F.Cu" "F.Mask" "F.Paste")
			(net 667 "/DRAM + SRAM/SRAM.A8")
			(pinfunction "IO_L10N_T1_D15_14")
			(pintype "bidirectional")
			(die_length 13.845)
			(solder_mask_margin 0.02)
		)
		(pad "R27" smd circle
			(at 11.5 -0.5)
			(size 0.5 0.5)
			(property pad_prop_bga)
			(layers "F.Cu" "F.Mask" "F.Paste")
			(net 24 "+3V3")
			(pinfunction "VCCO_14")
			(pintype "passive")
			(solder_mask_margin 0.02)
		)
		(pad "R28" smd circle
			(at 12.5 -0.5)
			(size 0.5 0.5)
			(property pad_prop_bga)
			(layers "F.Cu" "F.Mask" "F.Paste")
			(net 668 "/DRAM + SRAM/SRAM.DQ6")
			(pinfunction "IO_L11P_T1_SRCC_14")
			(pintype "bidirectional")
			(die_length 14.17)
			(solder_mask_margin 0.02)
		)
		(pad "R29" smd circle
			(at 13.5 -0.5)
			(size 0.5 0.5)
			(property pad_prop_bga)
			(layers "F.Cu" "F.Mask" "F.Paste")
			(net 669 "/DRAM + SRAM/SRAM.DQ7")
			(pinfunction "IO_L7N_T1_D10_14")
			(pintype "bidirectional")
			(die_length 16.165)
			(solder_mask_margin 0.02)
		)
		(pad "R30" smd circle
			(at 14.5 -0.5)
			(size 0.5 0.5)
			(property pad_prop_bga)
			(layers "F.Cu" "F.Mask" "F.Paste")
			(net 670 "/DRAM + SRAM/SRAM.A9")
			(pinfunction "IO_L9P_T1_DQS_14")
			(pintype "bidirectional")
			(die_length 16.981)
			(solder_mask_margin 0.02)
		)
		(pad "T1" smd circle
			(at -14.5 0.5)
			(size 0.5 0.5)
			(property pad_prop_bga)
			(layers "F.Cu" "F.Mask" "F.Paste")
			(net 124 "/FMC+ HSPC/GTX115.TX0_N")
			(pinfunction "MGTXTXN3_115")
			(pintype "bidirectional")
			(die_length 13.793)
			(solder_mask_margin 0.02)
		)
		(pad "T2" smd circle
			(at -13.5 0.5)
			(size 0.5 0.5)
			(property pad_prop_bga)
			(layers "F.Cu" "F.Mask" "F.Paste")
			(net 122 "/FMC+ HSPC/GTX115.TX0_P")
			(pinfunction "MGTXTXP3_115")
			(pintype "bidirectional")
			(die_length 13.764)
			(solder_mask_margin 0.02)
		)
		(pad "T3" smd circle
			(at -12.5 0.5)
			(size 0.5 0.5)
			(property pad_prop_bga)
			(layers "F.Cu" "F.Mask" "F.Paste")
			(net 8 "+1V2_MGTAVTT")
			(pinfunction "MGTAVTT")
			(pintype "passive")
			(solder_mask_margin 0.02)
		)
		(pad "T4" smd circle
			(at -11.5 0.5)
			(size 0.5 0.5)
			(property pad_prop_bga)
			(layers "F.Cu" "F.Mask" "F.Paste")
			(net 1 "GND")
			(pinfunction "GND")
			(pintype "passive")
			(solder_mask_margin 0.02)
		)
		(pad "T5" smd circle
			(at -10.5 0.5)
			(size 0.5 0.5)
			(property pad_prop_bga)
			(layers "F.Cu" "F.Mask" "F.Paste")
			(net 490 "/FMC+ HSPC/GTX116.RX0_N")
			(pinfunction "MGTXRXN0_116")
			(pintype "bidirectional")
			(die_length 12.339)
			(solder_mask_margin 0.02)
		)
		(pad "T6" smd circle
			(at -9.5 0.5)
			(size 0.5 0.5)
			(property pad_prop_bga)
			(layers "F.Cu" "F.Mask" "F.Paste")
			(net 249 "/FMC+ HSPC/GTX116.RX0_P")
			(pinfunction "MGTXRXP0_116")
			(pintype "bidirectional")
			(die_length 12.521)
			(solder_mask_margin 0.02)
		)
		(pad "T7" smd circle
			(at -8.5 0.5)
			(size 0.5 0.5)
			(property pad_prop_bga)
			(layers "F.Cu" "F.Mask" "F.Paste")
			(net 26 "+1V8")
			(pinfunction "MGTVCCAUX")
			(pintype "bidirectional")
			(solder_mask_margin 0.02)
		)
		(pad "T8" smd circle
			(at -7.5 0.5)
			(size 0.5 0.5)
			(property pad_prop_bga)
			(layers "F.Cu" "F.Mask" "F.Paste")
			(net 1 "GND")
			(pinfunction "GND")
			(pintype "passive")
			(solder_mask_margin 0.02)
		)
		(pad "T9" smd circle
			(at -6.5 0.5)
			(size 0.5 0.5)
			(property pad_prop_bga)
			(layers "F.Cu" "F.Mask" "F.Paste")
			(net 24 "+3V3")
			(pinfunction "VCCO_0")
			(pintype "passive")
			(solder_mask_margin 0.02)
		)
		(pad "T10" smd circle
			(at -5.5 0.5)
			(size 0.5 0.5)
			(property pad_prop_bga)
			(layers "F.Cu" "F.Mask" "F.Paste")
			(net 1 "GND")
			(pinfunction "GND")
			(pintype "passive")
			(solder_mask_margin 0.02)
		)
		(pad "T11" smd circle
			(at -4.5 0.5)
			(size 0.5 0.5)
			(property pad_prop_bga)
			(layers "F.Cu" "F.Mask" "F.Paste")
			(net 650 "+1V0")
			(pinfunction "VCCINT")
			(pintype "passive")
			(solder_mask_margin 0.02)
		)
		(pad "T12" smd circle
			(at -3.5 0.5)
			(size 0.5 0.5)
			(property pad_prop_bga)
			(layers "F.Cu" "F.Mask" "F.Paste")
			(net 1 "GND")
			(pinfunction "GND")
			(pintype "passive")
			(solder_mask_margin 0.02)
		)
		(pad "T13" smd circle
			(at -2.5 0.5)
			(size 0.5 0.5)
			(property pad_prop_bga)
			(layers "F.Cu" "F.Mask" "F.Paste")
			(net 26 "+1V8")
			(pinfunction "VCCAUX")
			(pintype "passive")
			(solder_mask_margin 0.02)
		)
		(pad "T14" smd circle
			(at -1.5 0.5)
			(size 0.5 0.5)
			(property pad_prop_bga)
			(layers "F.Cu" "F.Mask" "F.Paste")
			(net 1396 "unconnected-(U1I-VN_0-PadT14)")
			(pinfunction "VN_0")
			(pintype "bidirectional+no_connect")
			(die_length 10.582)
			(solder_mask_margin 0.02)
		)
		(pad "T15" smd circle
			(at -0.5 0.5)
			(size 0.5 0.5)
			(property pad_prop_bga)
			(layers "F.Cu" "F.Mask" "F.Paste")
			(net 649 "VREFP")
			(pinfunction "VREFP_0")
			(pintype "bidirectional")
			(die_length 10.695)
			(solder_mask_margin 0.02)
		)
		(pad "T16" smd circle
			(at 0.5 0.5)
			(size 0.5 0.5)
			(property pad_prop_bga)
			(layers "F.Cu" "F.Mask" "F.Paste")
			(net 1 "GND")
			(pinfunction "GND")
			(pintype "passive")
			(solder_mask_margin 0.02)
		)
		(pad "T17" smd circle
			(at 1.5 0.5)
			(size 0.5 0.5)
			(property pad_prop_bga)
			(layers "F.Cu" "F.Mask" "F.Paste")
			(net 650 "+1V0")
			(pinfunction "VCCINT")
			(pintype "passive")
			(solder_mask_margin 0.02)
		)
		(pad "T18" smd circle
			(at 2.5 0.5)
			(size 0.5 0.5)
			(property pad_prop_bga)
			(layers "F.Cu" "F.Mask" "F.Paste")
			(net 1 "GND")
			(pinfunction "GND")
			(pintype "passive")
			(solder_mask_margin 0.02)
		)
		(pad "T19" smd circle
			(at 3.5 0.5)
			(size 0.5 0.5)
			(property pad_prop_bga)
			(layers "F.Cu" "F.Mask" "F.Paste")
			(net 1 "GND")
			(pinfunction "GND")
			(pintype "passive")
			(solder_mask_margin 0.02)
		)
		(pad "T20" smd circle
			(at 4.5 0.5)
			(size 0.5 0.5)
			(property pad_prop_bga)
			(layers "F.Cu" "F.Mask" "F.Paste")
			(net 1385 "/SUP_MCU.SPARE3")
			(pinfunction "IO_L4P_T0_D04_14")
			(pintype "bidirectional")
			(die_length 9.515)
			(solder_mask_margin 0.02)
		)
		(pad "T21" smd circle
			(at 5.5 0.5)
			(size 0.5 0.5)
			(property pad_prop_bga)
			(layers "F.Cu" "F.Mask" "F.Paste")
			(net 1295 "/USB_SPI.MOSI")
			(pinfunction "IO_L4N_T0_D05_14")
			(pintype "bidirectional")
			(die_length 8.352)
			(solder_mask_margin 0.02)
		)
		(pad "T22" smd circle
			(at 6.5 0.5)
			(size 0.5 0.5)
			(property pad_prop_bga)
			(layers "F.Cu" "F.Mask" "F.Paste")
			(net 1296 "/USB_SPI.SCK")
			(pinfunction "IO_L5P_T0_D06_14")
			(pintype "bidirectional")
			(die_length 8.945)
			(solder_mask_margin 0.02)
		)
		(pad "T23" smd circle
			(at 7.5 0.5)
			(size 0.5 0.5)
			(property pad_prop_bga)
			(layers "F.Cu" "F.Mask" "F.Paste")
			(net 1297 "/USB_SPI.~{CS}")
			(pinfunction "IO_L5N_T0_D07_14")
			(pintype "bidirectional")
			(die_length 9.494)
			(solder_mask_margin 0.02)
		)
		(pad "T24" smd circle
			(at 8.5 0.5)
			(size 0.5 0.5)
			(property pad_prop_bga)
			(layers "F.Cu" "F.Mask" "F.Paste")
			(net 24 "+3V3")
			(pinfunction "VCCO_14")
			(pintype "passive")
			(solder_mask_margin 0.02)
		)
		(pad "T25" smd circle
			(at 9.5 0.5)
			(size 0.5 0.5)
			(property pad_prop_bga)
			(layers "F.Cu" "F.Mask" "F.Paste")
			(net 671 "/DRAM + SRAM/SRAM.A2")
			(pinfunction "IO_L14P_T2_SRCC_14")
			(pintype "bidirectional")
			(die_length 11.691)
			(solder_mask_margin 0.02)
		)
		(pad "T26" smd circle
			(at 10.5 0.5)
			(size 0.5 0.5)
			(property pad_prop_bga)
			(layers "F.Cu" "F.Mask" "F.Paste")
			(net 672 "/DRAM + SRAM/SRAM.A3")
			(pinfunction "IO_L12P_T1_MRCC_14")
			(pintype "bidirectional")
			(die_length 14.679)
			(solder_mask_margin 0.02)
		)
		(pad "T27" smd circle
			(at 11.5 0.5)
			(size 0.5 0.5)
			(property pad_prop_bga)
			(layers "F.Cu" "F.Mask" "F.Paste")
			(net 673 "/DRAM + SRAM/SRAM.A13")
			(pinfunction "IO_L12N_T1_MRCC_14")
			(pintype "bidirectional")
			(die_length 14.259)
			(solder_mask_margin 0.02)
		)
		(pad "T28" smd circle
			(at 12.5 0.5)
			(size 0.5 0.5)
			(property pad_prop_bga)
			(layers "F.Cu" "F.Mask" "F.Paste")
			(net 674 "/DRAM + SRAM/SRAM.DQ5")
			(pinfunction "IO_L11N_T1_SRCC_14")
			(pintype "bidirectional")
			(die_length 14.716)
			(solder_mask_margin 0.02)
		)
		(pad "T29" smd circle
			(at 13.5 0.5)
			(size 0.5 0.5)
			(property pad_prop_bga)
			(layers "F.Cu" "F.Mask" "F.Paste")
			(net 1 "GND")
			(pinfunction "GND")
			(pintype "passive")
			(solder_mask_margin 0.02)
		)
		(pad "T30" smd circle
			(at 14.5 0.5)
			(size 0.5 0.5)
			(property pad_prop_bga)
			(layers "F.Cu" "F.Mask" "F.Paste")
			(net 675 "/DRAM + SRAM/SRAM.A15")
			(pinfunction "IO_L9N_T1_DQS_D13_14")
			(pintype "bidirectional")
			(die_length 17.602)
			(solder_mask_margin 0.02)
		)
		(pad "U1" smd circle
			(at -14.5 1.5)
			(size 0.5 0.5)
			(property pad_prop_bga)
			(layers "F.Cu" "F.Mask" "F.Paste")
			(net 1 "GND")
			(pinfunction "GND")
			(pintype "passive")
			(solder_mask_margin 0.02)
		)
		(pad "U2" smd circle
			(at -13.5 1.5)
			(size 0.5 0.5)
			(property pad_prop_bga)
			(layers "F.Cu" "F.Mask" "F.Paste")
			(net 1 "GND")
			(pinfunction "GND")
			(pintype "passive")
			(solder_mask_margin 0.02)
		)
		(pad "U3" smd circle
			(at -12.5 1.5)
			(size 0.5 0.5)
			(property pad_prop_bga)
			(layers "F.Cu" "F.Mask" "F.Paste")
			(net 89 "/FMC+ HSPC/GTX115.TX3_N")
			(pinfunction "MGTXTXN2_115")
			(pintype "bidirectional")
			(die_length 12.101)
			(solder_mask_margin 0.02)
		)
		(pad "U4" smd circle
			(at -11.5 1.5)
			(size 0.5 0.5)
			(property pad_prop_bga)
			(layers "F.Cu" "F.Mask" "F.Paste")
			(net 87 "/FMC+ HSPC/GTX115.TX3_P")
			(pinfunction "MGTXTXP2_115")
			(pintype "bidirectional")
			(die_length 12.157)
			(solder_mask_margin 0.02)
		)
		(pad "U5" smd circle
			(at -10.5 1.5)
			(size 0.5 0.5)
			(property pad_prop_bga)
			(layers "F.Cu" "F.Mask" "F.Paste")
			(net 8 "+1V2_MGTAVTT")
			(pinfunction "MGTAVTT")
			(pintype "passive")
			(solder_mask_margin 0.02)
		)
		(pad "U6" smd circle
			(at -9.5 1.5)
			(size 0.5 0.5)
			(property pad_prop_bga)
			(layers "F.Cu" "F.Mask" "F.Paste")
			(net 1 "GND")
			(pinfunction "GND")
			(pintype "passive")
			(solder_mask_margin 0.02)
		)
	)
)
